# T6G (Grand Teton) — schematic netlist excerpt (pin names and nets, part order shuffled) for the footprints in the layout excerpt that follows; sources: Cadence DE-HDL packaged netlist, KiCad conversion of 04192023_DAF0TMB3IC0_F0TG_MB_C_brd_V02_OCP.brd

PR8091  Q_RES  11.8K 0.1% CHIP  pkg 0402LF  page 189 : A = P5V_AUX_FB ; B = GND
C754  Q_CAP_DIFFBUS  DIFF BUS_0.22UF 6.3V 20% X6S  pkg C0201  page 66 : \1\ = P5E_CPU1_P2_TX_C_DN<9> ; \2\ = P5E_CPU1_P2_TX_DN<9>
PR323  Q_RES  5.6 1% CHIP  pkg 0402LF  page 194 : A = SW_PVDDCR_CPU0_P0_BOOT2 ; B = SW_PVDDCR_CPU0_P0_BOOT2_RC

(kicad_pcb
	(version 20260206)
	(generator "pcbnew")
	(generator_version "10.0")
	(general
		(thickness 1.6)
		(legacy_teardrops no)
	)
	(paper "A4")
	(title_block
		(title "04192023_DAF0TMB3IC0_F0TG_MB_C_brd_V02_OCP.brd")
		(comment 1 "Grand Teton / footprints 4183-4185 of 8354")
	)
	(layers
		(0 "F.Cu" signal "TOP")
		(4 "In1.Cu" signal "GND")
		(6 "In2.Cu" signal "IN1")
		(8 "In3.Cu" signal "GND1")
		(10 "In4.Cu" signal "IN2")
		(12 "In5.Cu" signal "GND2")
		(14 "In6.Cu" signal "IN3")
		(16 "In7.Cu" signal "GND3")
		(18 "In8.Cu" signal "VCC")
		(20 "In9.Cu" signal "VCC1")
		(22 "In10.Cu" signal "GND4")
		(24 "In11.Cu" signal "IN4")
		(26 "In12.Cu" signal "GND5")
		(28 "In13.Cu" signal "IN5")
		(30 "In14.Cu" signal "GND6")
		(32 "In15.Cu" signal "IN6")
		(34 "In16.Cu" signal "GND7")
		(2 "B.Cu" signal "BOTTOM")
		(9 "F.Adhes" user "F.Adhesive")
		(11 "B.Adhes" user "B.Adhesive")
		(13 "F.Paste" user "Package Geometry/Pastemask Top")
		(15 "B.Paste" user "Package Geometry/Pastemask Bottom")
		(5 "F.SilkS" user "Ref Des/Silkscreen Top")
		(7 "B.SilkS" user "Ref Des/Silkscreen Bottom")
		(1 "F.Mask" user "Board Geometry/Soldermask Top")
		(3 "B.Mask" user "Board Geometry/Soldermask Bottom")
		(17 "Dwgs.User" user "User.Drawings")
		(19 "Cmts.User" user "User.Comments")
		(21 "Eco1.User" user "User.Eco1")
		(23 "Eco2.User" user "User.Eco2")
		(25 "Edge.Cuts" user "Board Geometry/Outline")
		(27 "Margin" user)
		(31 "F.CrtYd" user "Package Geometry/Place Bound Top")
		(29 "B.CrtYd" user "Package Geometry/Place Bound Bottom")
		(35 "F.Fab" user "Ref Des/Assembly Top")
		(33 "B.Fab" user "Ref Des/Assembly Bottom")
	)
	(footprint ""
		(layer "F.Cu")
		(at 158.848044 -370.57203 -90)
		(property "Reference" "C754"
			(at 0 0 270)
			(layer "F.SilkS")
			(hide yes)
			(effects
				(font
					(size 1.27 1.27)
				)
			)
		)
		(property "Value" ""
			(at 0 0 270)
			(layer "F.Fab")
			(effects
				(font
					(size 1.27 1.27)
				)
			)
		)
		(duplicate_pad_numbers_are_jumpers no)
		(fp_line
			(start -0.299974 0.150114)
			(end -0.299974 -0.150114)
			(stroke
				(width 0.1)
				(type default)
			)
			(layer "F.Fab")
		)
		(fp_line
			(start 0.299974 0.150114)
			(end -0.299974 0.150114)
			(stroke
				(width 0.1)
				(type default)
			)
			(layer "F.Fab")
		)
		(fp_line
			(start -0.299974 -0.150114)
			(end 0.299974 -0.150114)
			(stroke
				(width 0.1)
				(type default)
			)
			(layer "F.Fab")
		)
		(fp_line
			(start 0.299974 -0.150114)
			(end 0.299974 0.150114)
			(stroke
				(width 0.1)
				(type default)
			)
			(layer "F.Fab")
		)
		(pad "1" smd rect
			(at -0.2667 0 270)
			(size 0.3048 0.381)
			(layers "F.Cu" "F.Mask" "F.Paste")
			(net "P5E_CPU1_P2_TX_C_DN<9>")
		)
		(pad "2" smd rect
			(at 0.2667 0 270)
			(size 0.3048 0.381)
			(layers "F.Cu" "F.Mask" "F.Paste")
			(net "P5E_CPU1_P2_TX_DN<9>")
		)
	)
	(footprint ""
		(layer "F.Cu")
		(at 371.915944 -178.0921 -90)
		(property "Reference" "PR323"
			(at 0 0 270)
			(layer "F.SilkS")
			(hide yes)
			(effects
				(font
					(size 1.27 1.27)
				)
			)
		)
		(property "Value" ""
			(at 0 0 270)
			(layer "F.Fab")
			(effects
				(font
					(size 1.27 1.27)
				)
			)
		)
		(duplicate_pad_numbers_are_jumpers no)
		(fp_line
			(start -0.7874 0.4064)
			(end -0.7874 -0.4064)
			(stroke
				(width 0.1524)
				(type default)
			)
			(layer "F.SilkS")
		)
		(fp_line
			(start 0.7874 0.4064)
			(end -0.7874 0.4064)
			(stroke
				(width 0.1524)
				(type default)
			)
			(layer "F.SilkS")
		)
		(fp_line
			(start -0.7874 -0.4064)
			(end 0.7874 -0.4064)
			(stroke
				(width 0.1524)
				(type default)
			)
			(layer "F.SilkS")
		)
		(fp_line
			(start 0.7874 -0.4064)
			(end 0.7874 0.4064)
			(stroke
				(width 0.1524)
				(type default)
			)
			(layer "F.SilkS")
		)
		(fp_line
			(start -0.67945 0.3048)
			(end -0.67945 -0.305054)
			(stroke
				(width 0.1)
				(type default)
			)
			(layer "F.Fab")
		)
		(fp_line
			(start -0.12065 0.3048)
			(end -0.67945 0.3048)
			(stroke
				(width 0.1)
				(type default)
			)
			(layer "F.Fab")
		)
		(fp_line
			(start 0.120396 0.3048)
			(end 0.120396 0.2794)
			(stroke
				(width 0.1)
				(type default)
			)
			(layer "F.Fab")
		)
		(fp_line
			(start 0.67945 0.3048)
			(end 0.120396 0.3048)
			(stroke
				(width 0.1)
				(type default)
			)
			(layer "F.Fab")
		)
		(fp_line
			(start -0.12065 0.2794)
			(end -0.12065 0.3048)
			(stroke
				(width 0.1)
				(type default)
			)
			(layer "F.Fab")
		)
		(fp_line
			(start 0.120396 0.2794)
			(end -0.12065 0.2794)
			(stroke
				(width 0.1)
				(type default)
			)
			(layer "F.Fab")
		)
		(fp_line
			(start -0.12065 -0.2794)
			(end 0.12065 -0.2794)
			(stroke
				(width 0.1)
				(type default)
			)
			(layer "F.Fab")
		)
		(fp_line
			(start 0.12065 -0.2794)
			(end 0.12065 -0.3048)
			(stroke
				(width 0.1)
				(type default)
			)
			(layer "F.Fab")
		)
		(fp_line
			(start 0.12065 -0.3048)
			(end 0.67945 -0.3048)
			(stroke
				(width 0.1)
				(type default)
			)
			(layer "F.Fab")
		)
		(fp_line
			(start 0.67945 -0.3048)
			(end 0.67945 0.3048)
			(stroke
				(width 0.1)
				(type default)
			)
			(layer "F.Fab")
		)
		(fp_line
			(start -0.67945 -0.305054)
			(end -0.12065 -0.305054)
			(stroke
				(width 0.1)
				(type default)
			)
			(layer "F.Fab")
		)
		(fp_line
			(start -0.12065 -0.305054)
			(end -0.12065 -0.2794)
			(stroke
				(width 0.1)
				(type default)
			)
			(layer "F.Fab")
		)
		(pad "1" smd circle
			(at -0.40005 0 270)
			(size 0 0)
			(layers "F.Cu" "F.Mask" "F.Paste")
			(net "SW_PVDDCR_CPU0_P0_BOOT2")
		)
		(pad "2" smd circle
			(at 0.40005 0 270)
			(size 0 0)
			(layers "F.Cu" "F.Mask" "F.Paste")
			(net "SW_PVDDCR_CPU0_P0_BOOT2_RC")
		)
	)
	(footprint ""
		(layer "F.Cu")
		(at 409.792424 -139.362942 89.946)
		(property "Reference" "PR8091"
			(at 0 0 89.946)
			(layer "F.SilkS")
			(hide yes)
			(effects
				(font
					(size 1.27 1.27)
				)
			)
		)
		(property "Value" ""
			(at 0 0 89.946)
			(layer "F.Fab")
			(effects
				(font
					(size 1.27 1.27)
				)
			)
		)
		(duplicate_pad_numbers_are_jumpers no)
		(fp_line
			(start -0.787275 -0.40642)
			(end 0.787525 -0.40638)
			(stroke
				(width 0.1524)
				(type default)
			)
			(layer "F.SilkS")
		)
		(fp_line
			(start 0.787525 -0.40638)
			(end 0.787275 0.40642)
			(stroke
				(width 0.1524)
				(type default)
			)
			(layer "F.SilkS")
		)
		(fp_line
			(start -0.787525 0.40638)
			(end -0.787275 -0.40642)
			(stroke
				(width 0.1524)
				(type default)
			)
			(layer "F.SilkS")
		)
		(fp_line
			(start 0.787275 0.40642)
			(end -0.787525 0.40638)
			(stroke
				(width 0.1524)
				(type default)
			)
			(layer "F.SilkS")
		)
		(fp_line
			(start -0.679484 -0.305176)
			(end -0.120683 -0.30494)
			(stroke
				(width 0.1)
				(type default)
			)
			(layer "F.Fab")
		)
		(fp_line
			(start -0.120683 -0.30494)
			(end -0.120659 -0.279286)
			(stroke
				(width 0.1)
				(type default)
			)
			(layer "F.Fab")
		)
		(fp_line
			(start 0.120617 -0.304914)
			(end 0.679417 -0.304678)
			(stroke
				(width 0.1)
				(type default)
			)
			(layer "F.Fab")
		)
		(fp_line
			(start 0.679417 -0.304678)
			(end 0.679484 0.304922)
			(stroke
				(width 0.1)
				(type default)
			)
			(layer "F.Fab")
		)
		(fp_line
			(start 0.120641 -0.279514)
			(end 0.120617 -0.304914)
			(stroke
				(width 0.1)
				(type default)
			)
			(layer "F.Fab")
		)
		(fp_line
			(start -0.120659 -0.279286)
			(end 0.120641 -0.279514)
			(stroke
				(width 0.1)
				(type default)
			)
			(layer "F.Fab")
		)
		(fp_line
			(start 0.120405 0.279287)
			(end -0.120641 0.279514)
			(stroke
				(width 0.1)
				(type default)
			)
			(layer "F.Fab")
		)
		(fp_line
			(start -0.120641 0.279514)
			(end -0.120617 0.304914)
			(stroke
				(width 0.1)
				(type default)
			)
			(layer "F.Fab")
		)
		(fp_line
			(start -0.679417 0.304678)
			(end -0.679484 -0.305176)
			(stroke
				(width 0.1)
				(type default)
			)
			(layer "F.Fab")
		)
		(fp_line
			(start 0.120429 0.304687)
			(end 0.120405 0.279287)
			(stroke
				(width 0.1)
				(type default)
			)
			(layer "F.Fab")
		)
		(fp_line
			(start -0.120617 0.304914)
			(end -0.679417 0.304678)
			(stroke
				(width 0.1)
				(type default)
			)
			(layer "F.Fab")
		)
		(fp_line
			(start 0.679484 0.304922)
			(end 0.120429 0.304687)
			(stroke
				(width 0.1)
				(type default)
			)
			(layer "F.Fab")
		)
		(pad "1" smd circle
			(at -0.40005 0 89.946)
			(size 0 0)
			(layers "F.Cu" "F.Mask" "F.Paste")
			(net "P5V_AUX_FB")
		)
		(pad "2" smd circle
			(at 0.40005 0 89.946)
			(size 0 0)
			(layers "F.Cu" "F.Mask" "F.Paste")
			(net "GND")
		)
	)
)
